FILE_TYPE = MULTI_PHYS_TABLE;
PART 'TTL1G86'
{============================================================================================================================================================================}
:VALUE|PACK_TYPE|MATERIAL|PART_NUMBER= EnvComp |PART_NUMBER|JEDEC_TYPE|CLASS|DESCRIPTION|HEIGHT|COMPONENT_TYPE|LEAD_LENGTH| LPID   | SPEED_URL | Status |RPL| AML | Bus_Unit | Days ;
{============================================================================================================================================================================}
'74AHCT1G86' | 'SOTLF'   | 'IC'     | 'D39848-001'(!) = 'YES;YES;UNK;UNK;ok;VLD' | 'D39848-001' | 'SSOP5_53_65MA' | 'IC'  | 'SINGLE 2 INPUT XOR' | '0.043 IN' | 'SMALLSMT'        | '' | '' | 'http://speed.intel.com:8081/speed/module/pdm/item/pdm_item_detail_direct.asp?item_cde=D39848-001&item_rev=01&url_param=unused' | 'Design' | 'YES' | '1' | 'SMO_IC' | '84' 
'74AHCT1G86' | 'SOTLF'   | 'EMPTY'  | 'D39848-001'(!) = 'YES;YES;UNK;UNK;ok;VLD' | 'D39848-001' | 'SSOP5_53_65MA' | 'IO'  | 'SINGLE 2 INPUT XOR' | '0.043 IN' | 'SMALLSMT'        | '' | '' | 'http://speed.intel.com:8081/speed/module/pdm/item/pdm_item_detail_direct.asp?item_cde=D39848-001&item_rev=01&url_param=unused' | 'Design' | 'YES' | '1' | 'SMO_IC' | '84' 
END_PART
END.
